FILE_TYPE = MULTI_PHYS_TABLE;

PART 'Q_CAP_DIFFBUS'

{========================================================================================}
:VALUE             | VOLTAGE | TOLERANCE | PACK_TYPE | MATERIAL | PART_NUMBER        = STANDARD        | LIFECYCLE      | ASS_PART | PART_NUMBER   | JEDEC_TYPE       | DESCRIPTION                                          | MANUFTR | MANUF_PN            | RD_CMPLS_LVL | CMPLS_LVL | CLASS      | DIP_SMD | FROM_PJ        | DATA                             | FP_ECN                      | EE_CHECK_LIST | PSL | STATUS | CREATOR | CREATEDAY  ;
{========================================================================================}
 'DIFF BUS_0.1UF'  | '16V'   | '10%'     | 'C0402'   | 'X7R'    | 'SP_CH4103K1B09'(!) = 'End of Design' | 'Comp-Approve' | 'SELASS' | 'CH4103K1B09' |'C0402_DIFF-BUS'| 'CAP CHIP 0.1U 16V(10%.X7R.0402)SEL-ASS'             | 'MUR'   | 'GRM155R71C104K'    | 'PF(V1)'     | 'PF(V1)'  | 'DISCRETE' | ''      | 'T2R-YAO-HSUN' | 'MUR_LF_CAP SERIES_20100122.pdf' | '0402 SERIES_LL34.xls'      | ''            | ''  | ''     | ''      | '20131204'
 'DIFF BUS_0.1UF'  | '16V'   | '10%'     | 'C0402'   | 'EMPTY'  | 'SP_CH4103K1B09'(!) = 'End of Design' | 'Comp-Approve' | 'SELASS' | 'CH4103K1B09' |'C0402_DIFF-BUS'| 'CAP CHIP 0.1U 16V(10%.X7R.0402)SEL-ASS'             | 'MUR'   | 'GRM155R71C104K'    | 'PF(V1)'     | 'PF(V1)'  | 'DISCRETE' | ''      | 'T2R-YAO-HSUN' | 'MUR_LF_CAP SERIES_20100122.pdf' | '0402 SERIES_LL34.xls'      | ''            | ''  | ''     | ''      | '20131204'
 'DIFF BUS_0.22UF' | '16V'   | '10%'     | 'C0402'   | 'X7R'    | 'SP_CH4223K1B00'(!) = 'End of Design' | 'Comp-Approve' | ''       | 'CH4223K1B00' |'C0402_DIFF-BUS'| 'CAP CHIP 0.22U 16V(10%.X7R.0402)_FOR DIFF BUS'      | 'MUR'   | 'GRM155R71C224K'    | 'EU(V1)'     | ''        | 'DISCRETE' | ''      | 'T2R-YAO-HSUN' | 'AC Coupling.msg'                | '0402 SERIES_LL34.xls'      | ''            | ''  | ''     | ''      | '20131204'
 'DIFF BUS_0.22UF' | '16V'   | '10%'     | 'C0402'   | 'EMPTY'  | 'SP_CH4223K1B00'(!) = 'End of Design' | 'Comp-Approve' | ''       | 'CH4223K1B00' |'C0402_DIFF-BUS'| 'CAP CHIP 0.22U 16V(10%.X7R.0402)_FOR DIFF BUS'      | 'MUR'   | 'GRM155R71C224K'    | 'EU(V1)'     | ''        | 'DISCRETE' | ''      | 'T2R-YAO-HSUN' | 'AC Coupling.msg'                | '0402 SERIES_LL34.xls'      | ''            | ''  | ''     | ''      | '20131204'
 'DIFF BUS_0.1UF'  | '16V'   | '10%'     | 'C0402'   | 'X7R'    | 'SP_CH4103K1B08'(!) = ''              | ''             | ''       | 'CH4103K1B08' |'C0402_DIFF-BUS'| 'CAP CHIP 0.1U 16V(10%.X7R.0402)_FOR DIFF BUS'       | 'MUR'   | 'WBM155R71C104K'    | 'EP(V1)'     | 'EP(V1)'  | 'DISCRETE' | ''      | 'S5M-GLEN'     | 'MUR_LF_CAP SERIES_1.pdf'        | '0402 SERIES_LL34.xls'      | ''            | ''  | ''     | ''      | '20150105'
 'DIFF BUS_0.1UF'  | '16V'   | '10%'     | 'C0402'   | 'EMPTY'  | 'SP_CH4103K1B08'(!) = ''              | ''             | ''       | 'CH4103K1B08' |'C0402_DIFF-BUS'| 'CAP CHIP 0.1U 16V(10%.X7R.0402)_FOR DIFF BUS'       | 'MUR'   | 'WBM155R71C104K'    | 'EP(V1)'     | 'EP(V1)'  | 'DISCRETE' | ''      | 'S5M-GLEN'     | 'MUR_LF_CAP SERIES_1.pdf'        | '0402 SERIES_LL34.xls'      | ''            | ''  | ''     | ''      | '20150105'
 'DIFF BUS_0.22UF' | '6.3V'  | '10%'     | 'C0201'   | 'X5R'    | 'SP_CH4221K9E00'(!) = ''              | ''             | ''       | 'CH4221K9E00' |'C0201_DIFF-BUS'| 'CAP CHIP 0.22UF 6.3V(+-10%,X5R,0201)_FOR DIFF BUS'  | 'MUR'   | 'GRM033R60J224K'    | 'EU(V1)'     | ''        | 'DISCRETE' | ''      | 'CJ2A-KEVIN'   | 'AC Coupling.msg'                | 'DCN-all 0201 RCL part.doc' | ''            | ''  | ''     | ''      | '20150511'
 'DIFF BUS_0.22UF' | '6.3V'  | '10%'     | 'C0201'   | 'EMPTY'  | 'SP_CH4221K9E00'(!) = ''              | ''             | ''       | 'CH4221K9E00' |'C0201_DIFF-BUS'| 'CAP CHIP 0.22UF 6.3V(+-10%,X5R,0201)_FOR DIFF BUS'  | 'MUR'   | 'GRM033R60J224K'    | 'EU(V1)'     | ''        | 'DISCRETE' | ''      | 'CJ2A-KEVIN'   | 'AC Coupling.msg'                | 'DCN-all 0201 RCL part.doc' | ''            | ''  | ''     | ''      | '20150511'
 'DIFF BUS_0.1UF'  | '16V'   | '10%'     | 'C0402'   | 'X7R'    | 'SP_CH4103K1B14'(!) = 'End of Design' | 'Comp-Approve' | ''       | 'CH4103K1B14' |'C0402_DIFF-BUS'| 'CAP CHIP 0.1U 16V(10%,X7R,0402)MUR'                 | 'MUR'   | 'GRM155R71C104K'    | 'EP(V1)'     | ''        | 'DISCRETE' | ''      | 'T2H-CF'       | 'AC Coupling.msg'                | '0402 SERIES_LL34.xls'      | ''            | ''  | ''     | ''      | '20150603'
 'DIFF BUS_0.1UF'  | '16V'   | '10%'     | 'C0402'   | 'EMPTY'  | 'SP_CH4103K1B14'(!) = 'End of Design' | 'Comp-Approve' | ''       | 'CH4103K1B14' |'C0402_DIFF-BUS'| 'CAP CHIP 0.1U 16V(10%,X7R,0402)MUR'                 | 'MUR'   | 'GRM155R71C104K'    | 'EP(V1)'     | ''        | 'DISCRETE' | ''      | 'T2H-CF'       | 'AC Coupling.msg'                | '0402 SERIES_LL34.xls'      | ''            | ''  | ''     | ''      | '20150603'
 'DIFF BUS_0.22UF' | '16V'   | '10%'     | 'C0402'   | 'X7R'    | 'SP_CH4223K1B04'(!) = 'End of Design' | 'Comp-Approve' | ''       | 'CH4223K1B04' |'C0402_DIFF-BUS'| 'CAP CHIP 0.22U 16V(10%,X7R,0402)MUR'                | 'MUR'   | 'GRM155R71C224K'    | 'EP(V1)'     | ''        | 'DISCRETE' | ''      | 'T2H-CF'       | 'AC Coupling.msg'                | '0402 SERIES_LL34.xls'      | ''            | ''  | ''     | ''      | '20150603'
 'DIFF BUS_0.22UF' | '16V'   | '10%'     | 'C0402'   | 'EMPTY'  | 'SP_CH4223K1B04'(!) = 'End of Design' | 'Comp-Approve' | ''       | 'CH4223K1B04' |'C0402_DIFF-BUS'| 'CAP CHIP 0.22U 16V(10%,X7R,0402)MUR'                | 'MUR'   | 'GRM155R71C224K'    | 'EP(V1)'     | ''        | 'DISCRETE' | ''      | 'T2H-CF'       | 'AC Coupling.msg'                | '0402 SERIES_LL34.xls'      | ''            | ''  | ''     | ''      | '20150603'
 'DIFF BUS_0.22UF' | '6.3V'  | '20%'     | 'C0201'   | 'X6S'    | 'SP_CH4221MEE01'(!) = ''              | ''             | ''       | 'CH4221MEE01' |'C0201_DIFF-BUS'| 'CAP CHIP 0.22UF 6.3V(20%,X6S,0201)_DIFF BUS'        | 'TDK'   | 'C0603X6S0J224MT-A' | 'EP(V1)'     | 'EP(V1)'  | 'DISCRETE' | ''      | 'CJ2A-KEVIN'   | 'AC Coupling.msg'                | 'DCN-all 0201 RCL part.doc' | ''            | ''  | ''     | ''      | '20150629'
 'DIFF BUS_0.22UF' | '6.3V'  | '20%'     | 'C0201'   | 'EMPTY'  | 'SP_CH4221MEE01'(!) = ''              | ''             | ''       | 'CH4221MEE01' |'C0201_DIFF-BUS'| 'CAP CHIP 0.22UF 6.3V(20%,X6S,0201)_DIFF BUS'        | 'TDK'   | 'C0603X6S0J224MT-A' | 'EP(V1)'     | 'EP(V1)'  | 'DISCRETE' | ''      | 'CJ2A-KEVIN'   | 'AC Coupling.msg'                | 'DCN-all 0201 RCL part.doc' | ''            | ''  | ''     | ''      | '20150629'
 'DIFF BUS_0.22UF' | '16V'   | '10%'     | 'C0402'   | 'X7R'    | 'SP_CH4223K1B06'(!) = ''              | ''             | 'AEC'    | 'CH4223K1B06' |'C0402_DIFF-BUS'| 'CAP CHIP 0.22U 16V(10%,X7R,0402)AEC)_DIFF BUS'      | 'MUR'   | 'GCM155R71C224K'    | 'EP(V1)'     | 'EP(V1)'  | 'DISCRETE' | ''      | 'T2HV-RONNY'   | 'AC Coupling.msg'                | '0402 SERIES_LL34.xls'      | ''            | ''  | ''     | ''      | '20150511'
 'DIFF BUS_0.22UF' | '16V'   | '10%'     | 'C0402'   | 'EMPTY'  | 'SP_CH4223K1B06'(!) = ''              | ''             | 'AEC'    | 'CH4223K1B06' |'C0402_DIFF-BUS'| 'CAP CHIP 0.22U 16V(10%,X7R,0402)AEC)_DIFF BUS'      | 'MUR'   | 'GCM155R71C224K'    | 'EP(V1)'     | 'EP(V1)'  | 'DISCRETE' | ''      | 'T2HV-RONNY'   | 'AC Coupling.msg'                | '0402 SERIES_LL34.xls'      | ''            | ''  | ''     | ''      | '20150511'
 'DIFF BUS_0.1UF'  | '16V'   | '10%'     | 'C0402'   | 'X7R'    | 'SP_CH4103K1B21'(!) = ''              | ''             | 'AEC'    | 'CH4103K1B21' |'C0402_DIFF-BUS'| 'CAP CHIP 0.1U 16V(+-10%,X7R,0402)AEC_DIFF BUS'      | 'YGO'   | 'AC0402KRX7R7BB104' | 'EP(V1)'     | ''        | 'DISCRETE' | ''      | 'T2HV-RONNY'   | 'AC Coupling.msg'                | '0402 SERIES_LL34.xls'      | ''            | ''  | ''     | ''      | '20150511'
 'DIFF BUS_0.1UF'  | '16V'   | '10%'     | 'C0402'   | 'EMPTY'  | 'SP_CH4103K1B21'(!) = ''              | ''             | 'AEC'    | 'CH4103K1B21' |'C0402_DIFF-BUS'| 'CAP CHIP 0.1U 16V(+-10%,X7R,0402)AEC_DIFF BUS'      | 'YGO'   | 'AC0402KRX7R7BB104' | 'EP(V1)'     | ''        | 'DISCRETE' | ''      | 'T2HV-RONNY'   | 'AC Coupling.msg'                | '0402 SERIES_LL34.xls'      | ''            | ''  | ''     | ''      | '20150511'
 'DIFF BUS_0.1UF'  | '16V'   | '10%'     | 'C0402'   | 'X7R'    | 'SP_CH4103K1B22'(!) = 'End of Design' | 'Comp-Approve' | 'AEC'    | 'CH4103K1B22' |'C0402_DIFF-BUS'| 'CAP CHIP 0.1U 16V(10%,X7R,0402)MUR_AEC_DIFF BUS'    | 'MUR'   | 'GCM155R71C104K'    | 'EP(V1)'     | ''        | 'DISCRETE' | ''      | 'T2HV-RONNY'   | ''                               | ''                          | ''            | ''  | ''     | ''      | '20150518'
 'DIFF BUS_0.1UF'  | '16V'   | '10%'     | 'C0402'   | 'EMPTY'  | 'SP_CH4103K1B22'(!) = 'End of Design' | 'Comp-Approve' | 'AEC'    | 'CH4103K1B22' |'C0402_DIFF-BUS'| 'CAP CHIP 0.1U 16V(10%,X7R,0402)MUR_AEC_DIFF BUS'    | 'MUR'   | 'GCM155R71C104K'    | 'EP(V1)'     | ''        | 'DISCRETE' | ''      | 'T2HV-RONNY'   | ''                               | ''                          | ''            | ''  | ''     | ''      | '20150518'
 'DIFF BUS_0.22UF' | '16V'   | '10%'     | 'C0402'   | 'X7R'    | 'SP_CH4223K1B07'(!) = ''              | ''             | 'AEC'    | 'CH4223K1B07' |'C0402_DIFF-BUS'| 'CAP CHIP 0.22U 16V(10%,X7R,0402)MUR_AEC_DIFF BUS'   | 'MUR'   | 'GCM155R71C224K'    | 'EP(V1)'     | ''        | 'DISCRETE' | ''      | 'T2HV-RONNY'   | ''                               | ''                          | ''            | ''  | ''     | ''      | '20150518'
 'DIFF BUS_0.22UF' | '16V'   | '10%'     | 'C0402'   | 'EMPTY'  | 'SP_CH4223K1B07'(!) = ''              | ''             | 'AEC'    | 'CH4223K1B07' |'C0402_DIFF-BUS'| 'CAP CHIP 0.22U 16V(10%,X7R,0402)MUR_AEC_DIFF BUS'   | 'MUR'   | 'GCM155R71C224K'    | 'EP(V1)'     | ''        | 'DISCRETE' | ''      | 'T2HV-RONNY'   | ''                               | ''                          | ''            | ''  | ''     | ''      | '20150518'
 'DIFF BUS_0.33UF' | '6.3V'  | '10%'     | 'C0402'   | 'X6S'    | 'SP_CH4331KEB01'(!) = 'End of Design' | 'Comp-Approve' | ''       | 'CH4331KEB01' |'C0402_DIFF-BUS'| 'CAP CHIP 0.33UF 6.3V(10%,X6S,0402)_FOR DIFF BUS'    | 'MUR'   | 'GRM155C80J334K'    | 'EP(V1)'     | 'EP(V1)'  | 'DISCRETE' | ''      | 'S5R-ROGER'    | ''                               | ''                          | ''            | ''  | ''     | ''      | '20180504'
 'DIFF BUS_0.33UF' | '6.3V'  | '10%'     | 'C0402'   | 'EMPTY'  | 'SP_CH4331KEB01'(!) = 'End of Design' | 'Comp-Approve' | ''       | 'CH4331KEB01' |'C0402_DIFF-BUS'| 'CAP CHIP 0.33UF 6.3V(10%,X6S,0402)_FOR DIFF BUS'    | 'MUR'   | 'GRM155C80J334K'    | 'EP(V1)'     | 'EP(V1)'  | 'DISCRETE' | ''      | 'S5R-ROGER'    | ''                               | ''                          | ''            | ''  | ''     | ''      | '20180504'
 'DIFF BUS_0.01UF' | '16V'   | '10%'     | 'C0402'   | 'X7R'    | 'SP_CH3103K1B15_3'(!) = 'End of Design' | 'Comp-Approve' | ''       | 'CH3103K1B15' |'C0402_DIFF-BUS'| 'CAP CHIP 0.01U 16V(10%,X7R,0402)_FOR DIFF BUS'      | 'MUR'   | 'GRM155R71C103K'    | 'EP(V1)'     | 'EP(V1)'  | 'DISCRETE' | ''      | 'S5R-ROGER'    | ''                               | ''                          | ''            | ''  | ''     | ''      | '20180516'
 'DIFF BUS_0.01UF' | '16V'   | '10%'     | 'C0402'   | 'EMPTY'  | 'SP_CH3103K1B15_3'(!) = 'End of Design' | 'Comp-Approve' | ''       | 'CH3103K1B15' |'C0402_DIFF-BUS'| 'CAP CHIP 0.01U 16V(10%,X7R,0402)_FOR DIFF BUS'      | 'MUR'   | 'GRM155R71C103K'    | 'EP(V1)'     | 'EP(V1)'  | 'DISCRETE' | ''      | 'S5R-ROGER'    | ''                               | ''                          | ''            | ''  | ''     | ''      | '20180516'
 'DIFF BUS_0.22UF' | '6.3V'  | '10%'     | 'C0201'   | 'X6S'    | 'SP_CH4221KEE00'(!) = ''              | ''             | ''       | 'CH4221KEE00' |'C0201_DIFF-BUS'| 'CAP CHIP 0.22UF 6.3V(+-10%,X6S,0201)_DIFF BUS'      | 'MUR'   | 'GRM033C80J224K'    | 'EP(V1)'     | 'EP(V1)'  | 'DISCRETE' | ''      | 'T2M-MARK'     | 'AC Coupling.msg'                | 'DCN-all 0201 RCL part.doc' | ''            | ''  | ''     | ''      | '20190827'
 'DIFF BUS_0.22UF' | '6.3V'  | '10%'     | 'C0201'   | 'EMPTY'  | 'SP_CH4221KEE00'(!) = ''              | ''             | ''       | 'CH4221KEE00' |'C0201_DIFF-BUS'| 'CAP CHIP 0.22UF 6.3V(+-10%,X6S,0201)_DIFF BUS'      | 'MUR'   | 'GRM033C80J224K'    | 'EP(V1)'     | 'EP(V1)'  | 'DISCRETE' | ''      | 'T2M-MARK'     | 'AC Coupling.msg'                | 'DCN-all 0201 RCL part.doc' | ''            | ''  | ''     | ''      | '20190827'
 'DIFF BUS_0.1UF'  | '6.3V'  | '10%'     | 'C0201'   | 'X6S'    | 'SP_CH4101KEE02'(!) = ''              | ''             | ''       | 'CH4101KEE02' |'C0201_DIFF-BUS'| 'CAP CHIP 0.1UF 6.3V(10%,X6S,0201)SAM_DIFF BUS'      | 'SAM'   | 'CL03X104KQ3NNNC'   | 'EP(V1)'     | 'EP(V1)'  | 'DISCRETE' | ''      | 'S8I-KATE'     | 'AC Coupling.msg'                | 'DCN-all 0201 RCL part.doc' | ''            | ''  | ''     | ''      | '20191008'
 'DIFF BUS_0.1UF'  | '6.3V'  | '10%'     | 'C0201'   | 'EMPTY'  | 'SP_CH4101KEE02'(!) = ''              | ''             | ''       | 'CH4101KEE02' |'C0201_DIFF-BUS'| 'CAP CHIP 0.1UF 6.3V(10%,X6S,0201)SAM_DIFF BUS'      | 'SAM'   | 'CL03X104KQ3NNNC'   | 'EP(V1)'     | 'EP(V1)'  | 'DISCRETE' | ''      | 'S8I-KATE'     | 'AC Coupling.msg'                | 'DCN-all 0201 RCL part.doc' | ''            | ''  | ''     | ''      | '20191008'
 'DIFF BUS_0.22UF' | '6.3V'  | '10%'     | 'C0201'   | 'X6S'    | 'SP_CH4221KEE01'(!) = ''              | ''             | ''       | 'CH4221KEE01' |'C0201_DIFF-BUS'| 'CAP CHIP 0.22UF 6.3V(+-10%,X6S,0201)MUR_DIFF BUS'   | 'MUR'   | 'GRM033C80J224K'    | 'EP(V1)'     | 'EP(V1)'  | 'DISCRETE' | ''      | 'S8I-KATE'     | 'AC Coupling.msg'                | 'DCN-all 0201 RCL part.doc' | ''            | ''  | ''     | ''      | '20200224'
 'DIFF BUS_0.22UF' | '6.3V'  | '10%'     | 'C0201'   | 'EMPTY'  | 'SP_CH4221KEE01'(!) = ''              | ''             | ''       | 'CH4221KEE01' |'C0201_DIFF-BUS'| 'CAP CHIP 0.22UF 6.3V(+-10%,X6S,0201)MUR_DIFF BUS'   | 'MUR'   | 'GRM033C80J224K'    | 'EP(V1)'     | 'EP(V1)'  | 'DISCRETE' | ''      | 'S8I-KATE'     | 'AC Coupling.msg'                | 'DCN-all 0201 RCL part.doc' | ''            | ''  | ''     | ''      | '20200224'
 'DIFF BUS_0.22UF' | '6.3V'  | '10%'     | 'C0201'   | 'X6S'    | 'SP_CH4221KEE04'(!) = ''              | ''             | ''       | 'CH4221KEE04' |'C0201_DIFF-BUS'| 'CAP CHIP 0.22UF 6.3V(+-10%,X6S,0201)SAM_DIFF BUS'   | 'SAM'   | 'CL03X224KQ3NNWC'   | 'EP(V1)'     | 'EP(V1)'  | 'DISCRETE' | ''      | 'T6H-WILLY'    | 'AC Coupling.msg'                | 'DCN-all 0201 RCL part.doc' | ''            | ''  | ''     | ''      | '20221024'
 'DIFF BUS_0.22UF' | '6.3V'  | '10%'     | 'C0201'   | 'EMPTY'  | 'SP_CH4221KEE04'(!) = ''              | ''             | ''       | 'CH4221KEE04' |'C0201_DIFF-BUS'| 'CAP CHIP 0.22UF 6.3V(+-10%,X6S,0201)SAM_DIFF BUS'   | 'SAM'   | 'CL03X224KQ3NNWC'   | 'EP(V1)'     | 'EP(V1)'  | 'DISCRETE' | ''      | 'T6H-WILLY'    | 'AC Coupling.msg'                | 'DCN-all 0201 RCL part.doc' | ''            | ''  | ''     | ''      | '20221024'
 'DIFF BUS_0.33UF' | '6.3V'  | '10%'     | 'C0402'   | 'X6S'    | 'SP_CH4331KEB03'(!) = ''              | ''             | ''       | 'CH4331KEB03' |'C0402_DIFF-BUS'| 'CAP CHIP 0.33U 6.3V(+-10%,X6S,0402)API_DIFF BUS'    | 'API'   | 'C1005X6S334KCT'    | 'EP(V1)'     | 'EP(V1)'  | 'DISCRETE' | ''      | 'T6H-WILLY'    | 'API_C1005X6S334KCT.pdf'         | '0402 SERIES_LL34.xls'      | ''            | ''  | ''     | ''      | '20230207'
 'DIFF BUS_0.33UF' | '6.3V'  | '10%'     | 'C0402'   | 'EMPTY'  | 'SP_CH4331KEB03'(!) = ''              | ''             | ''       | 'CH4331KEB03' |'C0402_DIFF-BUS'| 'CAP CHIP 0.33U 6.3V(+-10%,X6S,0402)API_DIFF BUS'    | 'API'   | 'C1005X6S334KCT'    | 'EP(V1)'     | 'EP(V1)'  | 'DISCRETE' | ''      | 'T6H-WILLY'    | 'API_C1005X6S334KCT.pdf'         | '0402 SERIES_LL34.xls'      | ''            | ''  | ''     | ''      | '20230207'
 'DIFF BUS_0.33UF' | '6.3V'  | '10%'     | 'C0402'   | 'X6S'    | 'SP_CH4331KEB02'(!) = ''              | ''             | ''       | 'CH4331KEB02' |'C0402_DIFF-BUS'| 'CAP CHIP 0.33UF 6.3V(10%,X6S,0402)MUR_FOR DIFF BUS' | 'MUR'   | 'GRM155C80J334K'    | 'EP(V1)'     | 'EP(V1)'  | 'DISCRETE' | ''      | 'T6H-WILLY'    | 'MUR_GRM155C80J334K.pdf'         | '0402 SERIES_LL34.xls'      | ''            | ''  | ''     | ''      | '20230613'
 'DIFF BUS_0.33UF' | '6.3V'  | '10%'     | 'C0402'   | 'EMPTY'  | 'SP_CH4331KEB02'(!) = ''              | ''             | ''       | 'CH4331KEB02' |'C0402_DIFF-BUS'| 'CAP CHIP 0.33UF 6.3V(10%,X6S,0402)MUR_FOR DIFF BUS' | 'MUR'   | 'GRM155C80J334K'    | 'EP(V1)'     | 'EP(V1)'  | 'DISCRETE' | ''      | 'T6H-WILLY'    | 'MUR_GRM155C80J334K.pdf'         | '0402 SERIES_LL34.xls'      | ''            | ''  | ''     | ''      | '20230613'
 'DIFF BUS_0.33UF' | '6.3V'  | '10%'     | 'C0402'   | 'X5R'    | 'SP_CH4331K9B08'(!) = ''              | ''             | ''       | 'CH4331K9B08' |'C0402_DIFF-BUS'| 'CAP CHIP 0.33U 6.3V(10%,X5R,0402)MUR_FOR DIFF BUS'  | 'MUR'   | 'GRM155R60J334K'    | 'EP(V1)'     | 'EP(V1)'  | 'DISCRETE' | ''      | 'T6H-WILLY'    | 'MUR_GRM155R60J334K.pdf'         | '0402 SERIES_LL34.xls'      | ''            | ''  | ''     | ''      | '20230629'
 'DIFF BUS_0.33UF' | '6.3V'  | '10%'     | 'C0402'   | 'EMPTY'  | 'SP_CH4331K9B08'(!) = ''              | ''             | ''       | 'CH4331K9B08' |'C0402_DIFF-BUS'| 'CAP CHIP 0.33U 6.3V(10%,X5R,0402)MUR_FOR DIFF BUS'  | 'MUR'   | 'GRM155R60J334K'    | 'EP(V1)'     | 'EP(V1)'  | 'DISCRETE' | ''      | 'T6H-WILLY'    | 'MUR_GRM155R60J334K.pdf'         | '0402 SERIES_LL34.xls'      | ''            | ''  | ''     | ''      | '20230629'
 'DIFF BUS_0.33UF' | '6.3V'  | '10%'     | 'C0402'   | 'X5R'    | 'SP_CH4331K9B10'(!) = ''              | ''             | ''       | 'CH4331K9B10' |'C0402_DIFF-BUS'| 'CAP CHIP 0.33U 6.3V(10%,X5R,0402)YGO_FOR DIFF BUS'  | 'YGO'   | 'CC0402KRX5R5BB334' | 'EP(V1)'     | 'EP(V1)'  | 'DISCRETE' | ''      | 'T6H-WILLY'    | 'YGO_CC0402KRX5R5BB334.pdf'      | 'CC0402KRX5R5BB334.msg'     | ''            | ''  | ''     | ''      | '20230629'
 'DIFF BUS_0.33UF' | '6.3V'  | '10%'     | 'C0402'   | 'EMPTY'  | 'SP_CH4331K9B10'(!) = ''              | ''             | ''       | 'CH4331K9B10' |'C0402_DIFF-BUS'| 'CAP CHIP 0.33U 6.3V(10%,X5R,0402)YGO_FOR DIFF BUS'  | 'YGO'   | 'CC0402KRX5R5BB334' | 'EP(V1)'     | 'EP(V1)'  | 'DISCRETE' | ''      | 'T6H-WILLY'    | 'YGO_CC0402KRX5R5BB334.pdf'      | 'CC0402KRX5R5BB334.msg'     | ''            | ''  | ''     | ''      | '20230629'

END_PART

END.

